;LEADER: 12 
;HEADER: 
;CODE  : ASCII 
;FILE  : 9127_F0T_Expander_BD_F_v02_0110_1240-bd-18-11.drl for backdrilling ... from layer BOTTOM to layer GND4
;DESIGN: 9127_F0T_Expander_BD_F_v02_0110_1240.brd
;MUST-NOT-CUT-LAYER = IN3,  MAX_DRILL_DEPTH = 55.05 MILS,  MFG_STUB_LENGTH = 0.00 MILS
;   BackdrillSize 1. = 15.700000 Tolerance = +0.000000/-0.000000 NON_PLATED MILS Quantity = 384
;   BackdrillSize 2. = 17.700000 Tolerance = +0.000000/-0.000000 NON_PLATED MILS Quantity = 276
;   BackdrillSize 3. = 19.900000 Tolerance = +0.000000/-0.000000 NON_PLATED MILS Quantity = 128
%
G90
X0264762Y1093897
X0268503Y1101376
X0261023Y1101376
X0261023Y1105117
X0257282Y1093897
X0242321Y1093897
X0238582Y1105117
X0253543Y1101376
X0253543Y1105117
X0246062Y1101376
X0249802Y1093897
X0257282Y1097637
X0249802Y1097637
X0238582Y1101376
X0234841Y1097637
X0242321Y1097637
X0246062Y1105117
X0234841Y1093897
X0268503Y1105117
X0264762Y1097637
X0227362Y1250984
X0204921Y1254724
X0201181Y1247243
X0212401Y1250984
X0227362Y1254724
X0201181Y1243503
X0219881Y1254724
X0212401Y1254724
X0208661Y1247243
X0219881Y1250984
X0204921Y1250984
X0216141Y1243503
X0208661Y1243503
X0223622Y1247243
X0216141Y1247243
X0223622Y1243503
X0253543Y1243503
X0242322Y1254724
X0231102Y1247243
X0238582Y1243503
X0234842Y1254724
X0249803Y1254724
X0257283Y1254724
X0253543Y1247243
X0257283Y1250984
X0246062Y1247243
X0234842Y1250984
X0242322Y1250984
X0231102Y1243503
X0249803Y1250984
X0246062Y1243503
X0238582Y1247243
X0298425Y1131299
X0294684Y1131299
X0298425Y1123818
X0302165Y1127559
X0302165Y1135039
X0294684Y1123818
X0305905Y1135039
X0305905Y1127559
X0275984Y1101376
X0317125Y1097637
X0287203Y1097637
X0290944Y1105117
X0302164Y1093897
X0279723Y1097637
X0324606Y1101377
X0272243Y1093897
X0279723Y1093897
X0305905Y1101376
X0309644Y1093897
X0290944Y1101376
X0283464Y1105117
X0313385Y1105117
X0275984Y1105117
X0302165Y1112598
X0294684Y1097637
X0272243Y1097637
X0305905Y1120078
X0324606Y1090157
X0287203Y1093897
X0305905Y1105117
X0302164Y1097637
X0294684Y1116338
X0298425Y1116338
X0320866Y1101377
X0309644Y1097637
X0305905Y1112598
X0298425Y1101376
X0317125Y1093897
X0294684Y1093897
X0283464Y1101376
X0298425Y1105117
X0320866Y1090157
X0313385Y1101377
X0302165Y1120078
X0602165Y1213582
X0602165Y1206102
X0613386Y1209842
X0613386Y1202362
X0609646Y1202362
X0602165Y1198621
X0605905Y1213582
X0609646Y1194881
X0602165Y1191141
X0609646Y1187401
X0605905Y1198621
X0613386Y1194881
X0605905Y1191141
X0605905Y1206102
X0609646Y1209842
X0613386Y1187401
X0609646Y1217322
X0605905Y1221062
X0602165Y1221062
X0613386Y1217322
X0602165Y1247243
X0609646Y1250984
X0613386Y1243503
X0617126Y1254724
X0613386Y1247243
X0609646Y1254724
X0624606Y1250984
X0620866Y1247243
X0620866Y1243503
X0617126Y1250984
X0605905Y1247243
X0624606Y1254724
X0759252Y1127559
X0759252Y1135039
X0762992Y1127559
X0755512Y1131299
X0751771Y1123818
X0755512Y1123818
X0762992Y1135039
X0751771Y1131299
X0751771Y1093897
X0710630Y1101376
X0699408Y1093897
X0748031Y1101376
X0766731Y1093897
X0755512Y1101376
X0703149Y1101376
X0766731Y1097637
X0740551Y1101376
X0736810Y1093897
X0729330Y1093897
X0762992Y1120078
X0733071Y1101376
X0759252Y1120078
X0744290Y1097637
X0729330Y1097637
X0721849Y1093897
X0751771Y1116338
X0755512Y1116338
X0691928Y1097637
X0721849Y1097637
X0762992Y1112598
X0706889Y1097637
X0740551Y1105117
X0759251Y1093897
X0691928Y1093897
X0725590Y1105117
X0714369Y1093897
X0759251Y1097637
X0755512Y1105117
X0695669Y1105117
X0762992Y1105117
X0762992Y1101376
X0744290Y1093897
X0748031Y1105117
X0710630Y1105117
X0751771Y1097637
X0759252Y1112598
X0718110Y1101376
X0699408Y1097637
X0718110Y1105117
X0736810Y1097637
X0695669Y1101376
X0733071Y1105117
X0703149Y1105117
X0725590Y1101376
X0706889Y1093897
X0714369Y1097637
X0777953Y1090157
X0781693Y1090157
X0774212Y1093897
X0770472Y1105117
X0774212Y1097637
X0777953Y1101377
X0781693Y1101377
X0770472Y1101377
X1156495Y1250984
X1149015Y1250984
X1152755Y1247243
X1145275Y1243503
X1156495Y1254724
X1152755Y1243503
X1163976Y1254724
X1167716Y1243503
X1160235Y1243503
X1145275Y1247243
X1160235Y1247243
X1163976Y1250984
X1167716Y1247243
X1149015Y1254724
X1134054Y1254724
X1134054Y1250984
X1130314Y1243503
X1137795Y1247243
X1115354Y1247243
X1126574Y1250984
X1141535Y1250984
X1115354Y1243503
X1130314Y1247243
X1137795Y1243503
X1122834Y1247243
X1119094Y1254724
X1141535Y1254724
X1119094Y1250984
X1122834Y1243503
X1126574Y1254724
X1167716Y1101376
X1163975Y1097637
X1152755Y1105117
X1163975Y1093897
X1149014Y1093897
X1156494Y1097637
X1152755Y1101376
X1167716Y1105117
X1156494Y1093897
X1149014Y1097637
X1160235Y1101376
X1160235Y1105117
X1231298Y1097637
X1220078Y1120078
X1223817Y1097637
X1186416Y1097637
X1220078Y1112598
X1190157Y1105117
X1208857Y1097637
X1238779Y1090157
X1201376Y1097637
X1223817Y1093897
X1175196Y1101376
X1193896Y1093897
X1220078Y1101376
X1190157Y1101376
X1216337Y1097637
X1216338Y1112598
X1205117Y1101376
X1216338Y1120078
X1238779Y1101377
X1182676Y1101376
X1178935Y1093897
X1212598Y1116338
X1175196Y1105117
X1197637Y1101376
X1208857Y1116338
X1171455Y1097637
X1182676Y1105117
X1208857Y1093897
X1186416Y1093897
X1227558Y1105117
X1171455Y1093897
X1212598Y1105117
X1235039Y1101377
X1212598Y1101376
X1205117Y1105117
X1231298Y1093897
X1216337Y1093897
X1178935Y1097637
X1220078Y1105117
X1197637Y1105117
X1235039Y1090157
X1193896Y1097637
X1201376Y1093897
X1227558Y1101377
X1220078Y1127559
X1220078Y1135039
X1208857Y1131299
X1212598Y1131299
X1208857Y1123818
X1216338Y1135039
X1212598Y1123818
X1216338Y1127559
X1171456Y1254724
X1171456Y1250984
X1523819Y1254724
X1523819Y1250984
X1531299Y1254724
X1535039Y1247243
X1527559Y1247243
X1527559Y1243503
X1531299Y1250984
X1535039Y1243503
X1516338Y1247243
X1538779Y1254724
X1520078Y1247243
X1538779Y1250984
X1527559Y1187401
X1520078Y1213582
X1523819Y1217322
X1527559Y1209842
X1520078Y1191141
X1527559Y1194881
X1527559Y1202362
X1516338Y1221062
X1523819Y1209842
X1527559Y1217322
X1520078Y1206102
X1516338Y1206102
X1516338Y1191141
X1523819Y1202362
X1520078Y1198621
X1523819Y1194881
X1516338Y1213582
X1523819Y1187401
X1516338Y1198621
X1520078Y1221062
X1621062Y1097637
X1606101Y1097637
X1628542Y1097637
X1665944Y1116338
X1650983Y1097637
X1654724Y1101376
X1624803Y1105117
X1662204Y1101376
X1643503Y1093897
X1609842Y1105117
X1643503Y1097637
X1624803Y1101376
X1613581Y1097637
X1647244Y1105117
X1650983Y1093897
X1636022Y1097637
X1613581Y1093897
X1665944Y1097637
X1654724Y1105117
X1609842Y1101376
X1632283Y1101376
X1658463Y1093897
X1617322Y1101376
X1632283Y1105117
X1639763Y1105117
X1636022Y1093897
X1647244Y1101376
X1662204Y1105117
X1628542Y1093897
X1617322Y1105117
X1658463Y1097637
X1665944Y1093897
X1606101Y1093897
X1621062Y1093897
X1639763Y1101376
X1665944Y1131299
X1665944Y1123818
X1673425Y1135039
X1677165Y1127559
X1669685Y1123818
X1673425Y1127559
X1669685Y1131299
X1677165Y1135039
X1669685Y1116338
X1695866Y1101377
X1688385Y1093897
X1680904Y1093897
X1684645Y1105117
X1692126Y1090157
X1673425Y1120078
X1688385Y1097637
X1677165Y1101376
X1680904Y1097637
X1673424Y1093897
X1669685Y1101376
X1673424Y1097637
X1677165Y1105117
X1684645Y1101377
X1669685Y1105117
X1695866Y1090157
X1677165Y1112598
X1677165Y1120078
X1673425Y1112598
X1692126Y1101377
M00
X0039225Y1464845
X0035825Y1464845
X0007983Y1525635
X0007983Y1529035
X0138290Y0527694
X0148692Y0534806
X0148692Y0538206
X0138290Y0531094
X0148692Y0524033
X0138290Y0472787
X0148692Y0494073
X0148692Y0479899
X0138290Y0513521
X0138290Y0444033
X0138290Y0486960
X0138290Y0516921
X0138290Y0440633
X0148692Y0520633
X0148692Y0436921
X0148692Y0490673
X0138290Y0483560
X0138290Y0429860
X0138290Y0426460
X0148692Y0422747
X0148692Y0433521
X0148692Y0476499
X0138290Y0469387
X0148692Y0408574
X0140690Y0398113
X0138290Y0415687
X0148692Y0419347
X0140690Y0401513
X0148692Y0391001
X0148692Y0405174
X0138290Y0412287
X0148692Y0394401
X0331395Y0571991
X0331395Y0596938
X0331395Y0532725
X0320993Y0589825
X0331395Y0582765
X0320993Y0579052
X0320993Y0529013
X0331395Y0614511
X0320993Y0561479
X0320993Y0593225
X0331395Y0600338
X0331395Y0536125
X0331395Y0586165
X0320993Y0525613
X0320993Y0603999
X0331395Y0568591
X0331395Y0611111
X0320993Y0607399
X0320993Y0564879
X0320993Y0575652
X0331395Y0474418
X0331395Y0477818
X0331395Y0488591
X0320993Y0511439
X0331395Y0521952
X0320993Y0484879
X0331395Y0518552
X0320993Y0470706
X0331395Y0491991
X0320993Y0467306
X0320993Y0481479
X0320993Y0514839
X0389015Y0792725
X0392415Y0792725
X0545768Y0781600
X0549168Y0781600
X0605778Y0408574
X0595376Y0415687
X0605778Y0391001
X0605778Y0419347
X0605778Y0394401
X0597776Y0398113
X0605778Y0405174
X0597776Y0401513
X0595376Y0412287
X0595376Y0429860
X0595376Y0516921
X0595376Y0486960
X0605778Y0494073
X0595376Y0483560
X0595376Y0472787
X0595376Y0469387
X0605778Y0520633
X0605778Y0476499
X0605778Y0436921
X0595376Y0426460
X0595376Y0444033
X0595376Y0440633
X0595376Y0513521
X0605778Y0490673
X0605778Y0479899
X0605778Y0422747
X0605778Y0433521
X0605778Y0538206
X0605778Y0524033
X0595376Y0527694
X0595376Y0531094
X0605778Y0534806
X0778079Y0484879
X0778079Y0470706
X0778079Y0511439
X0778079Y0514839
X0788481Y0521952
X0788481Y0518552
X0778079Y0481479
X0788481Y0474418
X0788481Y0491991
X0788481Y0488591
X0778079Y0467306
X0788481Y0477818
X0788481Y0611111
X0778079Y0564879
X0788481Y0582765
X0778079Y0561479
X0778079Y0603999
X0788481Y0586165
X0788481Y0568591
X0778079Y0579052
X0778079Y0525613
X0788481Y0596938
X0788481Y0600338
X0778079Y0607399
X0788481Y0571991
X0778079Y0593225
X0778079Y0589825
X0788481Y0614511
X0778079Y0529013
X0788481Y0536125
X0788481Y0532725
X0778079Y0575652
X0939331Y0324044
X0942731Y0324044
X0939300Y0346363
X0942700Y0346363
X1062865Y0419347
X1054863Y0398113
X1062865Y0394401
X1062865Y0405174
X1054863Y0401513
X1062865Y0408574
X1062865Y0391001
X1052463Y0415687
X1052463Y0412287
X1052463Y0429860
X1052463Y0483560
X1062865Y0490673
X1052463Y0444033
X1052463Y0516921
X1062865Y0494073
X1062865Y0422747
X1062865Y0479899
X1052463Y0472787
X1052463Y0440633
X1062865Y0433521
X1052463Y0426460
X1062865Y0476499
X1052463Y0486960
X1062865Y0436921
X1052463Y0469387
X1062865Y0520633
X1052463Y0513521
X1052463Y0527694
X1062865Y0538206
X1062865Y0524033
X1062865Y0534806
X1052463Y0531094
X1235166Y0511439
X1235166Y0481479
X1235166Y0467306
X1245568Y0477818
X1245568Y0474418
X1245568Y0491991
X1235166Y0470706
X1235166Y0514839
X1245568Y0518552
X1245568Y0521952
X1245568Y0488591
X1235166Y0484879
X1245568Y0571991
X1245568Y0586165
X1235166Y0525613
X1245568Y0614511
X1235166Y0561479
X1245568Y0582765
X1235166Y0589825
X1245568Y0600338
X1235166Y0529013
X1245568Y0532725
X1245568Y0611111
X1235166Y0579052
X1235166Y0607399
X1245568Y0536125
X1235166Y0603999
X1245568Y0568591
X1245568Y0596938
X1235166Y0593225
X1235166Y0564879
X1235166Y0575652
X1519952Y0524033
X1519952Y0538206
X1509550Y0531094
X1519952Y0534806
X1509550Y0527694
X1519952Y0433521
X1509550Y0513521
X1509550Y0426460
X1509550Y0486960
X1509550Y0483560
X1509550Y0429860
X1519952Y0490673
X1509550Y0516921
X1509550Y0469387
X1519952Y0520633
X1509550Y0444033
X1509550Y0440633
X1519952Y0476499
X1509550Y0472787
X1519952Y0494073
X1519952Y0436921
X1519952Y0422747
X1519952Y0479899
X1519952Y0419347
X1519952Y0391001
X1511950Y0398113
X1519952Y0405174
X1519952Y0408574
X1511950Y0401513
X1509550Y0415687
X1509550Y0412287
X1519952Y0394401
X1582187Y-0030386
X1592187Y-0072706
X1592187Y-0069306
X1582187Y-0033786
X1702655Y0532725
X1702655Y0568591
X1702655Y0582765
X1692253Y0579052
X1692253Y0564879
X1702655Y0614511
X1702655Y0571991
X1692253Y0589825
X1702655Y0586165
X1702655Y0596938
X1692253Y0603999
X1702655Y0600338
X1692253Y0593225
X1692253Y0575652
X1692253Y0607399
X1692253Y0561479
X1692253Y0525613
X1702655Y0611111
X1692253Y0529013
X1702655Y0536125
X1702655Y0518552
X1692253Y0470706
X1702655Y0521952
X1692253Y0481479
X1702655Y0488591
X1692253Y0484879
X1692253Y0514839
X1702655Y0474418
X1692253Y0467306
X1702655Y0477818
X1692253Y0511439
X1702655Y0491991
X1736405Y-0072678
X1736405Y-0069278
X1801761Y-0030488
X1801761Y-0033888
M00
X0291771Y1570434
X0283110Y1566103
X0291771Y1565315
X0283110Y1560985
X0309094Y1570434
X0300433Y1566103
X0309094Y1565315
X0300433Y1560985
X0326417Y1570434
X0317756Y1566103
X0326417Y1565315
X0317756Y1560985
X0343740Y1570434
X0335078Y1566103
X0343740Y1565315
X0335078Y1560985
X0291771Y1483426
X0283110Y1479095
X0291771Y1478308
X0283110Y1473977
X0309094Y1483426
X0300433Y1479095
X0309094Y1478308
X0300433Y1473977
X0326417Y1483426
X0317756Y1479095
X0326417Y1478308
X0317756Y1473977
X0343740Y1483426
X0335078Y1479095
X0343740Y1478308
X0335078Y1473977
X0638228Y1514134
X0629567Y1509804
X0638228Y1509016
X0629567Y1504685
X0655551Y1514134
X0646890Y1509804
X0655551Y1509016
X0646890Y1504685
X0664213Y1509804
X0664213Y1504685
X0638228Y1616496
X0629567Y1612166
X0638228Y1611378
X0629567Y1607048
X0655551Y1616496
X0646890Y1612166
X0655551Y1611378
X0646890Y1607048
X0664213Y1612166
X0664213Y1607048
X0672874Y1616496
X0672874Y1611378
X0690197Y1616496
X0681535Y1612166
X0690197Y1611378
X0681535Y1607048
X0672874Y1514134
X0672874Y1509016
X0690197Y1514134
X0681535Y1509804
X0690197Y1509016
X0681535Y1504685
X1313740Y1570434
X1305079Y1566103
X1313740Y1565315
X1305079Y1560985
X1331063Y1570434
X1322402Y1566103
X1331063Y1565315
X1322402Y1560985
X1348386Y1570434
X1339725Y1566103
X1348386Y1565315
X1339725Y1560985
X1365709Y1570434
X1357047Y1566103
X1365709Y1565315
X1357047Y1560985
X1313740Y1483426
X1305079Y1479095
X1313740Y1478308
X1305079Y1473977
X1331063Y1483426
X1322402Y1479095
X1331063Y1478308
X1322402Y1473977
X1348386Y1483426
X1339725Y1479095
X1348386Y1478308
X1339725Y1473977
X1365709Y1483426
X1357047Y1479095
X1365709Y1478308
X1357047Y1473977
X1660196Y1514134
X1651535Y1509804
X1660196Y1509016
X1651535Y1504685
X1668858Y1509804
X1668858Y1504685
X1660196Y1616496
X1651535Y1612166
X1660196Y1611378
X1651535Y1607048
X1668858Y1612166
X1668858Y1607048
X1677519Y1616496
X1677519Y1611378
X1694842Y1616496
X1686181Y1612166
X1694842Y1611378
X1686181Y1607048
X1712165Y1616496
X1703503Y1612166
X1712165Y1611378
X1703503Y1607048
X1677519Y1514134
X1677519Y1509016
X1694842Y1514134
X1686181Y1509804
X1694842Y1509016
X1686181Y1504685
X1712165Y1514134
X1703503Y1509804
X1712165Y1509016
X1703503Y1504685
M30
